(kicad_pcb
	(version 20260206)
	(generator "pcbnew")
	(generator_version "10.0")
	(general
		(thickness 1.6)
		(legacy_teardrops no)
	)
	(paper "A4")
	(title_block
		(title "03242023_DA0F0TMBIJ0_F0T_Motherboard_J_brd_V01_OCP.brd")
		(comment 1 "Grand Teton / footprint 2188 of 6105 (J19), pads 1-112 of 291")
	)
	(layers
		(0 "F.Cu" signal "TOP")
		(4 "In1.Cu" signal "GND")
		(6 "In2.Cu" signal "IN1")
		(8 "In3.Cu" signal "GND1")
		(10 "In4.Cu" signal "IN2")
		(12 "In5.Cu" signal "GND2")
		(14 "In6.Cu" signal "IN3")
		(16 "In7.Cu" signal "GND3")
		(18 "In8.Cu" signal "VCC")
		(20 "In9.Cu" signal "VCC1")
		(22 "In10.Cu" signal "GND4")
		(24 "In11.Cu" signal "IN4")
		(26 "In12.Cu" signal "GND5")
		(28 "In13.Cu" signal "IN5")
		(30 "In14.Cu" signal "GND6")
		(32 "In15.Cu" signal "IN6")
		(34 "In16.Cu" signal "GND7")
		(2 "B.Cu" signal "BOTTOM")
		(9 "F.Adhes" user "F.Adhesive")
		(11 "B.Adhes" user "B.Adhesive")
		(13 "F.Paste" user "Package Geometry/Pastemask Top")
		(15 "B.Paste" user "Package Geometry/Pastemask Bottom")
		(5 "F.SilkS" user "Ref Des/Silkscreen Top")
		(7 "B.SilkS" user "Ref Des/Silkscreen Bottom")
		(1 "F.Mask" user "Board Geometry/Soldermask Top")
		(3 "B.Mask" user "Board Geometry/Soldermask Bottom")
		(17 "Dwgs.User" user "User.Drawings")
		(19 "Cmts.User" user "User.Comments")
		(21 "Eco1.User" user "User.Eco1")
		(23 "Eco2.User" user "User.Eco2")
		(25 "Edge.Cuts" user "Board Geometry/Outline")
		(27 "Margin" user)
		(31 "F.CrtYd" user "Package Geometry/Place Bound Top")
		(29 "B.CrtYd" user "Package Geometry/Place Bound Bottom")
		(35 "F.Fab" user "Ref Des/Assembly Top")
		(33 "B.Fab" user "Ref Des/Assembly Bottom")
	)
	(footprint ""
		(layer "F.Cu")
		(at 40.36568 -258.091686)
		(property "Reference" "J19"
			(at -5.21716 -81.970372 0)
			(unlocked yes)
			(layer "F.SilkS")
			(effects
				(font
					(size 0.7874 0.5842)
					(thickness 0.1524)
				)
				(justify left)
			)
		)
		(property "Value" ""
			(at 0 0 0)
			(layer "F.Fab")
			(effects
				(font
					(size 1.27 1.27)
				)
			)
		)
		(duplicate_pad_numbers_are_jumpers no)
		(pad "1" smd rect
			(at -2.050034 -63.324994 270)
			(size 0.519938 1.4986)
			(layers "F.Cu" "F.Mask" "F.Paste")
			(net "P12V_S3_AUX_CPU1_NVDIMM")
		)
		(pad "2" smd rect
			(at -2.050034 -62.47511 270)
			(size 0.519938 1.4986)
			(layers "F.Cu" "F.Mask" "F.Paste")
			(net "TP_CHB_CPU1_DIMM1_FRU_0")
		)
		(pad "3" smd rect
			(at -2.050034 -61.624972 270)
			(size 0.519938 1.4986)
			(layers "F.Cu" "F.Mask" "F.Paste")
			(net "P3V3_AUX")
		)
		(pad "4" smd rect
			(at -2.050034 -60.775088 270)
			(size 0.519938 1.4986)
			(layers "F.Cu" "F.Mask" "F.Paste")
			(net "I3C_SPD_DDRABCD_CPU1_LVC1_SCL_2")
		)
		(pad "5" smd rect
			(at -2.050034 -59.92495 270)
			(size 0.519938 1.4986)
			(layers "F.Cu" "F.Mask" "F.Paste")
			(net "I3C_SPD_DDRABCD_CPU1_LVC1_SDA")
		)
		(pad "6" smd rect
			(at -2.050034 -59.075066 270)
			(size 0.519938 1.4986)
			(layers "F.Cu" "F.Mask" "F.Paste")
			(net "GND")
		)
		(pad "7" smd rect
			(at -2.050034 -58.224928 270)
			(size 0.519938 1.4986)
			(layers "F.Cu" "F.Mask" "F.Paste")
			(net "M_B_CPU1_SA_DQ<0>")
		)
		(pad "8" smd rect
			(at -2.050034 -57.375044 270)
			(size 0.519938 1.4986)
			(layers "F.Cu" "F.Mask" "F.Paste")
			(net "GND")
		)
		(pad "9" smd rect
			(at -2.050034 -56.524906 270)
			(size 0.519938 1.4986)
			(layers "F.Cu" "F.Mask" "F.Paste")
			(net "M_B_CPU1_SA_DQ<1>")
		)
		(pad "10" smd rect
			(at -2.050034 -55.675022 270)
			(size 0.519938 1.4986)
			(layers "F.Cu" "F.Mask" "F.Paste")
			(net "GND")
		)
		(pad "11" smd rect
			(at -2.050034 -54.824884 270)
			(size 0.519938 1.4986)
			(layers "F.Cu" "F.Mask" "F.Paste")
			(net "M_B_CPU1_SA_DQS_DP<0>")
		)
		(pad "12" smd rect
			(at -2.050034 -53.975 270)
			(size 0.519938 1.4986)
			(layers "F.Cu" "F.Mask" "F.Paste")
			(net "M_B_CPU1_SA_DQS_DN<0>")
		)
		(pad "13" smd rect
			(at -2.050034 -53.125116 270)
			(size 0.519938 1.4986)
			(layers "F.Cu" "F.Mask" "F.Paste")
			(net "GND")
		)
		(pad "14" smd rect
			(at -2.050034 -52.274978 270)
			(size 0.519938 1.4986)
			(layers "F.Cu" "F.Mask" "F.Paste")
			(net "M_B_CPU1_SA_DQ<4>")
		)
		(pad "15" smd rect
			(at -2.050034 -51.425094 270)
			(size 0.519938 1.4986)
			(layers "F.Cu" "F.Mask" "F.Paste")
			(net "GND")
		)
		(pad "16" smd rect
			(at -2.050034 -50.574956 270)
			(size 0.519938 1.4986)
			(layers "F.Cu" "F.Mask" "F.Paste")
			(net "M_B_CPU1_SA_DQ<5>")
		)
		(pad "17" smd rect
			(at -2.050034 -49.725072 270)
			(size 0.519938 1.4986)
			(layers "F.Cu" "F.Mask" "F.Paste")
			(net "GND")
		)
		(pad "18" smd rect
			(at -2.050034 -48.874934 270)
			(size 0.519938 1.4986)
			(layers "F.Cu" "F.Mask" "F.Paste")
			(net "M_B_CPU1_SA_DQ<8>")
		)
		(pad "19" smd rect
			(at -2.050034 -48.02505 270)
			(size 0.519938 1.4986)
			(layers "F.Cu" "F.Mask" "F.Paste")
			(net "GND")
		)
		(pad "20" smd rect
			(at -2.050034 -47.174912 270)
			(size 0.519938 1.4986)
			(layers "F.Cu" "F.Mask" "F.Paste")
			(net "M_B_CPU1_SA_DQ<9>")
		)
		(pad "21" smd rect
			(at -2.050034 -46.325028 270)
			(size 0.519938 1.4986)
			(layers "F.Cu" "F.Mask" "F.Paste")
			(net "GND")
		)
		(pad "22" smd rect
			(at -2.050034 -45.47489 270)
			(size 0.519938 1.4986)
			(layers "F.Cu" "F.Mask" "F.Paste")
			(net "M_B_CPU1_SA_DQS_DP<1>")
		)
		(pad "23" smd rect
			(at -2.050034 -44.625006 270)
			(size 0.519938 1.4986)
			(layers "F.Cu" "F.Mask" "F.Paste")
			(net "M_B_CPU1_SA_DQS_DN<1>")
		)
		(pad "24" smd rect
			(at -2.050034 -43.775122 270)
			(size 0.519938 1.4986)
			(layers "F.Cu" "F.Mask" "F.Paste")
			(net "GND")
		)
		(pad "25" smd rect
			(at -2.050034 -42.924984 270)
			(size 0.519938 1.4986)
			(layers "F.Cu" "F.Mask" "F.Paste")
			(net "M_B_CPU1_SA_DQ<12>")
		)
		(pad "26" smd rect
			(at -2.050034 -42.0751 270)
			(size 0.519938 1.4986)
			(layers "F.Cu" "F.Mask" "F.Paste")
			(net "GND")
		)
		(pad "27" smd rect
			(at -2.050034 -41.224962 270)
			(size 0.519938 1.4986)
			(layers "F.Cu" "F.Mask" "F.Paste")
			(net "M_B_CPU1_SA_DQ<13>")
		)
		(pad "28" smd rect
			(at -2.050034 -40.375078 270)
			(size 0.519938 1.4986)
			(layers "F.Cu" "F.Mask" "F.Paste")
			(net "GND")
		)
		(pad "29" smd rect
			(at -2.050034 -39.52494 270)
			(size 0.519938 1.4986)
			(layers "F.Cu" "F.Mask" "F.Paste")
			(net "M_B_CPU1_SA_DQ<16>")
		)
		(pad "30" smd rect
			(at -2.050034 -38.675056 270)
			(size 0.519938 1.4986)
			(layers "F.Cu" "F.Mask" "F.Paste")
			(net "GND")
		)
		(pad "31" smd rect
			(at -2.050034 -37.824918 270)
			(size 0.519938 1.4986)
			(layers "F.Cu" "F.Mask" "F.Paste")
			(net "M_B_CPU1_SA_DQ<17>")
		)
		(pad "32" smd rect
			(at -2.050034 -36.975034 270)
			(size 0.519938 1.4986)
			(layers "F.Cu" "F.Mask" "F.Paste")
			(net "GND")
		)
		(pad "33" smd rect
			(at -2.050034 -36.124896 270)
			(size 0.519938 1.4986)
			(layers "F.Cu" "F.Mask" "F.Paste")
			(net "M_B_CPU1_SA_DQS_DP<2>")
		)
		(pad "34" smd rect
			(at -2.050034 -35.275012 270)
			(size 0.519938 1.4986)
			(layers "F.Cu" "F.Mask" "F.Paste")
			(net "M_B_CPU1_SA_DQS_DN<2>")
		)
		(pad "35" smd rect
			(at -2.050034 -34.425128 270)
			(size 0.519938 1.4986)
			(layers "F.Cu" "F.Mask" "F.Paste")
			(net "GND")
		)
		(pad "36" smd rect
			(at -2.050034 -33.57499 270)
			(size 0.519938 1.4986)
			(layers "F.Cu" "F.Mask" "F.Paste")
			(net "M_B_CPU1_SA_DQ<20>")
		)
		(pad "37" smd rect
			(at -2.050034 -32.725106 270)
			(size 0.519938 1.4986)
			(layers "F.Cu" "F.Mask" "F.Paste")
			(net "GND")
		)
		(pad "38" smd rect
			(at -2.050034 -31.874968 270)
			(size 0.519938 1.4986)
			(layers "F.Cu" "F.Mask" "F.Paste")
			(net "M_B_CPU1_SA_DQ<21>")
		)
		(pad "39" smd rect
			(at -2.050034 -31.025084 270)
			(size 0.519938 1.4986)
			(layers "F.Cu" "F.Mask" "F.Paste")
			(net "GND")
		)
		(pad "40" smd rect
			(at -2.050034 -30.174946 270)
			(size 0.519938 1.4986)
			(layers "F.Cu" "F.Mask" "F.Paste")
			(net "M_B_CPU1_SA_DQ<24>")
		)
		(pad "41" smd rect
			(at -2.050034 -29.325062 270)
			(size 0.519938 1.4986)
			(layers "F.Cu" "F.Mask" "F.Paste")
			(net "GND")
		)
		(pad "42" smd rect
			(at -2.050034 -28.474924 270)
			(size 0.519938 1.4986)
			(layers "F.Cu" "F.Mask" "F.Paste")
			(net "M_B_CPU1_SA_DQ<25>")
		)
		(pad "43" smd rect
			(at -2.050034 -27.62504 270)
			(size 0.519938 1.4986)
			(layers "F.Cu" "F.Mask" "F.Paste")
			(net "GND")
		)
		(pad "44" smd rect
			(at -2.050034 -26.774902 270)
			(size 0.519938 1.4986)
			(layers "F.Cu" "F.Mask" "F.Paste")
			(net "M_B_CPU1_SA_DQS_DP<3>")
		)
		(pad "45" smd rect
			(at -2.050034 -25.925018 270)
			(size 0.519938 1.4986)
			(layers "F.Cu" "F.Mask" "F.Paste")
			(net "M_B_CPU1_SA_DQS_DN<3>")
		)
		(pad "46" smd rect
			(at -2.050034 -25.07488 270)
			(size 0.519938 1.4986)
			(layers "F.Cu" "F.Mask" "F.Paste")
			(net "GND")
		)
		(pad "47" smd rect
			(at -2.050034 -24.224996 270)
			(size 0.519938 1.4986)
			(layers "F.Cu" "F.Mask" "F.Paste")
			(net "M_B_CPU1_SA_DQ<28>")
		)
		(pad "48" smd rect
			(at -2.050034 -23.375112 270)
			(size 0.519938 1.4986)
			(layers "F.Cu" "F.Mask" "F.Paste")
			(net "GND")
		)
		(pad "49" smd rect
			(at -2.050034 -22.524974 270)
			(size 0.519938 1.4986)
			(layers "F.Cu" "F.Mask" "F.Paste")
			(net "M_B_CPU1_SA_DQ<29>")
		)
		(pad "50" smd rect
			(at -2.050034 -21.67509 270)
			(size 0.519938 1.4986)
			(layers "F.Cu" "F.Mask" "F.Paste")
			(net "GND")
		)
		(pad "51" smd rect
			(at -2.050034 -20.824952 270)
			(size 0.519938 1.4986)
			(layers "F.Cu" "F.Mask" "F.Paste")
			(net "M_B_CPU1_SA_CB<0>")
		)
		(pad "52" smd rect
			(at -2.050034 -19.975068 270)
			(size 0.519938 1.4986)
			(layers "F.Cu" "F.Mask" "F.Paste")
			(net "GND")
		)
		(pad "53" smd rect
			(at -2.050034 -19.12493 270)
			(size 0.519938 1.4986)
			(layers "F.Cu" "F.Mask" "F.Paste")
			(net "M_B_CPU1_SA_CB<1>")
		)
		(pad "54" smd rect
			(at -2.050034 -18.275046 270)
			(size 0.519938 1.4986)
			(layers "F.Cu" "F.Mask" "F.Paste")
			(net "GND")
		)
		(pad "55" smd rect
			(at -2.050034 -17.424908 270)
			(size 0.519938 1.4986)
			(layers "F.Cu" "F.Mask" "F.Paste")
			(net "M_B_CPU1_SA_DQS_DP<4>")
		)
		(pad "56" smd rect
			(at -2.050034 -16.575024 270)
			(size 0.519938 1.4986)
			(layers "F.Cu" "F.Mask" "F.Paste")
			(net "M_B_CPU1_SA_DQS_DN<4>")
		)
		(pad "57" smd rect
			(at -2.050034 -15.724886 270)
			(size 0.519938 1.4986)
			(layers "F.Cu" "F.Mask" "F.Paste")
			(net "GND")
		)
		(pad "58" smd rect
			(at -2.050034 -14.875002 270)
			(size 0.519938 1.4986)
			(layers "F.Cu" "F.Mask" "F.Paste")
			(net "M_B_CPU1_SA_CB<4>")
		)
		(pad "59" smd rect
			(at -2.050034 -14.025118 270)
			(size 0.519938 1.4986)
			(layers "F.Cu" "F.Mask" "F.Paste")
			(net "GND")
		)
		(pad "60" smd rect
			(at -2.050034 -13.17498 270)
			(size 0.519938 1.4986)
			(layers "F.Cu" "F.Mask" "F.Paste")
			(net "M_B_CPU1_SA_CB<5>")
		)
		(pad "61" smd rect
			(at -2.050034 -12.325096 270)
			(size 0.519938 1.4986)
			(layers "F.Cu" "F.Mask" "F.Paste")
			(net "GND")
		)
		(pad "62" smd rect
			(at -2.050034 -11.474958 270)
			(size 0.519938 1.4986)
			(layers "F.Cu" "F.Mask" "F.Paste")
			(net "M_B_CPU1_ALERT_N")
		)
		(pad "63" smd rect
			(at -2.050034 -10.625074 270)
			(size 0.519938 1.4986)
			(layers "F.Cu" "F.Mask" "F.Paste")
			(net "GND")
		)
		(pad "64" smd rect
			(at -2.050034 -9.774936 270)
			(size 0.519938 1.4986)
			(layers "F.Cu" "F.Mask" "F.Paste")
			(net "M_B_CPU1_SA_CS_N<0>")
		)
		(pad "65" smd rect
			(at -2.050034 -8.925052 270)
			(size 0.519938 1.4986)
			(layers "F.Cu" "F.Mask" "F.Paste")
			(net "GND")
		)
		(pad "66" smd rect
			(at -2.050034 -8.074914 270)
			(size 0.519938 1.4986)
			(layers "F.Cu" "F.Mask" "F.Paste")
			(net "M_B_CPU1_SA_CA<0>")
		)
		(pad "67" smd rect
			(at -2.050034 -7.22503 270)
			(size 0.519938 1.4986)
			(layers "F.Cu" "F.Mask" "F.Paste")
			(net "GND")
		)
		(pad "68" smd rect
			(at -2.050034 -6.374892 270)
			(size 0.519938 1.4986)
			(layers "F.Cu" "F.Mask" "F.Paste")
			(net "M_B_CPU1_SA_CA<2>")
		)
		(pad "69" smd rect
			(at -2.050034 -5.525008 270)
			(size 0.519938 1.4986)
			(layers "F.Cu" "F.Mask" "F.Paste")
			(net "GND")
		)
		(pad "70" smd rect
			(at -2.050034 -4.675124 270)
			(size 0.519938 1.4986)
			(layers "F.Cu" "F.Mask" "F.Paste")
			(net "M_B_CPU1_SA_CA<4>")
		)
		(pad "71" smd rect
			(at -2.050034 -3.824986 270)
			(size 0.519938 1.4986)
			(layers "F.Cu" "F.Mask" "F.Paste")
			(net "GND")
		)
		(pad "72" smd rect
			(at -2.050034 -2.975102 270)
			(size 0.519938 1.4986)
			(layers "F.Cu" "F.Mask" "F.Paste")
			(net "M_B_CPU1_SA_CA<6>")
		)
		(pad "73" smd rect
			(at -2.050034 -2.124964 270)
			(size 0.519938 1.4986)
			(layers "F.Cu" "F.Mask" "F.Paste")
			(net "GND")
		)
		(pad "74" smd rect
			(at -2.050034 -1.27508 270)
			(size 0.519938 1.4986)
			(layers "F.Cu" "F.Mask" "F.Paste")
			(net "M_B_CPU1_SA_PAR")
		)
		(pad "75" smd rect
			(at -2.050034 -0.424942 270)
			(size 0.519938 1.4986)
			(layers "F.Cu" "F.Mask" "F.Paste")
			(net "GND")
		)
		(pad "76" smd rect
			(at -2.050034 5.525008 270)
			(size 0.519938 1.4986)
			(layers "F.Cu" "F.Mask" "F.Paste")
			(net "M_B_CPU1_SB_CA<0>")
		)
		(pad "77" smd rect
			(at -2.050034 6.374892 270)
			(size 0.519938 1.4986)
			(layers "F.Cu" "F.Mask" "F.Paste")
			(net "GND")
		)
		(pad "78" smd rect
			(at -2.050034 7.22503 270)
			(size 0.519938 1.4986)
			(layers "F.Cu" "F.Mask" "F.Paste")
			(net "M_B_CPU1_SB_CA<2>")
		)
		(pad "79" smd rect
			(at -2.050034 8.074914 270)
			(size 0.519938 1.4986)
			(layers "F.Cu" "F.Mask" "F.Paste")
			(net "GND")
		)
		(pad "80" smd rect
			(at -2.050034 8.925052 270)
			(size 0.519938 1.4986)
			(layers "F.Cu" "F.Mask" "F.Paste")
			(net "M_B_CPU1_SB_CA<4>")
		)
		(pad "81" smd rect
			(at -2.050034 9.774936 270)
			(size 0.519938 1.4986)
			(layers "F.Cu" "F.Mask" "F.Paste")
			(net "GND")
		)
		(pad "82" smd rect
			(at -2.050034 10.625074 270)
			(size 0.519938 1.4986)
			(layers "F.Cu" "F.Mask" "F.Paste")
			(net "M_B_CPU1_SB_CA<6>")
		)
		(pad "83" smd rect
			(at -2.050034 11.474958 270)
			(size 0.519938 1.4986)
			(layers "F.Cu" "F.Mask" "F.Paste")
			(net "GND")
		)
		(pad "84" smd rect
			(at -2.050034 12.325096 270)
			(size 0.519938 1.4986)
			(layers "F.Cu" "F.Mask" "F.Paste")
			(net "M_B_CPU1_SB_CS_N<0>")
		)
		(pad "85" smd rect
			(at -2.050034 13.17498 270)
			(size 0.519938 1.4986)
			(layers "F.Cu" "F.Mask" "F.Paste")
			(net "GND")
		)
		(pad "86" smd rect
			(at -2.050034 14.025118 270)
			(size 0.519938 1.4986)
			(layers "F.Cu" "F.Mask" "F.Paste")
			(net "M_B_CPU1_SA_RSP<0>")
		)
		(pad "87" smd rect
			(at -2.050034 14.875002 270)
			(size 0.519938 1.4986)
			(layers "F.Cu" "F.Mask" "F.Paste")
			(net "M_B_CPU1_SB_RSP<0>")
		)
		(pad "88" smd rect
			(at -2.050034 15.724886 270)
			(size 0.519938 1.4986)
			(layers "F.Cu" "F.Mask" "F.Paste")
			(net "GND")
		)
		(pad "89" smd rect
			(at -2.050034 16.575024 270)
			(size 0.519938 1.4986)
			(layers "F.Cu" "F.Mask" "F.Paste")
			(net "M_B_CPU1_SB_CB<4>")
		)
		(pad "90" smd rect
			(at -2.050034 17.424908 270)
			(size 0.519938 1.4986)
			(layers "F.Cu" "F.Mask" "F.Paste")
			(net "GND")
		)
		(pad "91" smd rect
			(at -2.050034 18.275046 270)
			(size 0.519938 1.4986)
			(layers "F.Cu" "F.Mask" "F.Paste")
			(net "M_B_CPU1_SB_CB<5>")
		)
		(pad "92" smd rect
			(at -2.050034 19.12493 270)
			(size 0.519938 1.4986)
			(layers "F.Cu" "F.Mask" "F.Paste")
			(net "GND")
		)
		(pad "93" smd rect
			(at -2.050034 19.975068 270)
			(size 0.519938 1.4986)
			(layers "F.Cu" "F.Mask" "F.Paste")
			(net "M_B_CPU1_SB_DQS_DP<9>")
		)
		(pad "94" smd rect
			(at -2.050034 20.824952 270)
			(size 0.519938 1.4986)
			(layers "F.Cu" "F.Mask" "F.Paste")
			(net "M_B_CPU1_SB_DQS_DN<9>")
		)
		(pad "95" smd rect
			(at -2.050034 21.67509 270)
			(size 0.519938 1.4986)
			(layers "F.Cu" "F.Mask" "F.Paste")
			(net "GND")
		)
		(pad "96" smd rect
			(at -2.050034 22.524974 270)
			(size 0.519938 1.4986)
			(layers "F.Cu" "F.Mask" "F.Paste")
			(net "M_B_CPU1_SB_CB<0>")
		)
		(pad "97" smd rect
			(at -2.050034 23.375112 270)
			(size 0.519938 1.4986)
			(layers "F.Cu" "F.Mask" "F.Paste")
			(net "GND")
		)
		(pad "98" smd rect
			(at -2.050034 24.224996 270)
			(size 0.519938 1.4986)
			(layers "F.Cu" "F.Mask" "F.Paste")
			(net "M_B_CPU1_SB_CB<1>")
		)
		(pad "99" smd rect
			(at -2.050034 25.07488 270)
			(size 0.519938 1.4986)
			(layers "F.Cu" "F.Mask" "F.Paste")
			(net "GND")
		)
		(pad "100" smd rect
			(at -2.050034 25.925018 270)
			(size 0.519938 1.4986)
			(layers "F.Cu" "F.Mask" "F.Paste")
			(net "M_B_CPU1_SB_DQ<0>")
		)
		(pad "101" smd rect
			(at -2.050034 26.774902 270)
			(size 0.519938 1.4986)
			(layers "F.Cu" "F.Mask" "F.Paste")
			(net "GND")
		)
		(pad "102" smd rect
			(at -2.050034 27.62504 270)
			(size 0.519938 1.4986)
			(layers "F.Cu" "F.Mask" "F.Paste")
			(net "M_B_CPU1_SB_DQ<1>")
		)
		(pad "103" smd rect
			(at -2.050034 28.474924 270)
			(size 0.519938 1.4986)
			(layers "F.Cu" "F.Mask" "F.Paste")
			(net "GND")
		)
		(pad "104" smd rect
			(at -2.050034 29.325062 270)
			(size 0.519938 1.4986)
			(layers "F.Cu" "F.Mask" "F.Paste")
			(net "M_B_CPU1_SB_DQS_DP<0>")
		)
		(pad "105" smd rect
			(at -2.050034 30.174946 270)
			(size 0.519938 1.4986)
			(layers "F.Cu" "F.Mask" "F.Paste")
			(net "M_B_CPU1_SB_DQS_DN<0>")
		)
		(pad "106" smd rect
			(at -2.050034 31.025084 270)
			(size 0.519938 1.4986)
			(layers "F.Cu" "F.Mask" "F.Paste")
			(net "GND")
		)
		(pad "107" smd rect
			(at -2.050034 31.874968 270)
			(size 0.519938 1.4986)
			(layers "F.Cu" "F.Mask" "F.Paste")
			(net "M_B_CPU1_SB_DQ<4>")
		)
		(pad "108" smd rect
			(at -2.050034 32.725106 270)
			(size 0.519938 1.4986)
			(layers "F.Cu" "F.Mask" "F.Paste")
			(net "GND")
		)
		(pad "109" smd rect
			(at -2.050034 33.57499 270)
			(size 0.519938 1.4986)
			(layers "F.Cu" "F.Mask" "F.Paste")
			(net "M_B_CPU1_SB_DQ<5>")
		)
		(pad "110" smd rect
			(at -2.050034 34.425128 270)
			(size 0.519938 1.4986)
			(layers "F.Cu" "F.Mask" "F.Paste")
			(net "GND")
		)
		(pad "111" smd rect
			(at -2.050034 35.275012 270)
			(size 0.519938 1.4986)
			(layers "F.Cu" "F.Mask" "F.Paste")
			(net "M_B_CPU1_SB_DQ<8>")
		)
		(pad "112" smd rect
			(at -2.050034 36.124896 270)
			(size 0.519938 1.4986)
			(layers "F.Cu" "F.Mask" "F.Paste")
			(net "GND")
		)
	)
)
